# BASEBOARD_FAB2 (Tioga Pass) — schematic netlist excerpt (pin names and nets, part order shuffled) for the footprints in the layout excerpt that follows; sources: Cadence DE-HDL packaged netlist, KiCad conversion of Wiwynn_Tioga_Pass_MB.brd

R2U14  RES  0.0 5% CHIP  pkg 0402  page 107 : A = P3E_CPU0_PE1_SS_RXP<0> ; B = P3E_CPU0_PE1_SS_R_RXP<0>
R1U28  1K82R2F-1-GP  1%  pkg SMD-RG  page 169 : \1\ = A_P5V_SCALED ; \2\ = GND
R1W12  RES  0.0 5% CHIP  pkg 0402  page 176 : A = FM_CPLD_USB_P0_EN_N ; B = FM_USB_P0_EN_R_N

(kicad_pcb
	(version 20260206)
	(generator "pcbnew")
	(generator_version "10.0")
	(general
		(thickness 1.6)
		(legacy_teardrops no)
	)
	(paper "A4")
	(title_block
		(title "Wiwynn_Tioga_Pass_MB.brd")
		(comment 1 "Tioga Pass / footprints 2614-2616 of 4770")
	)
	(layers
		(0 "F.Cu" signal "TOP")
		(4 "In1.Cu" signal "L2GND")
		(6 "In2.Cu" signal "L3")
		(8 "In3.Cu" signal "L4GND")
		(10 "In4.Cu" signal "L5")
		(12 "In5.Cu" signal "L6GND")
		(14 "In6.Cu" signal "L7VCC")
		(16 "In7.Cu" signal "L8VCC")
		(18 "In8.Cu" signal "L9GND")
		(20 "In9.Cu" signal "L10")
		(22 "In10.Cu" signal "L11GND")
		(24 "In11.Cu" signal "L12")
		(26 "In12.Cu" signal "L13GND")
		(2 "B.Cu" signal "BOTTOM")
		(9 "F.Adhes" user "F.Adhesive")
		(11 "B.Adhes" user "B.Adhesive")
		(13 "F.Paste" user "Package Geometry/Pastemask Top")
		(15 "B.Paste" user "Package Geometry/Pastemask Bottom")
		(5 "F.SilkS" user "Ref Des/Silkscreen Top")
		(7 "B.SilkS" user "Ref Des/Silkscreen Bottom")
		(1 "F.Mask" user "Board Geometry/Soldermask Top")
		(3 "B.Mask" user "Board Geometry/Soldermask Bottom")
		(17 "Dwgs.User" user "User.Drawings")
		(19 "Cmts.User" user "User.Comments")
		(21 "Eco1.User" user "User.Eco1")
		(23 "Eco2.User" user "User.Eco2")
		(25 "Edge.Cuts" user "Board Geometry/Outline")
		(27 "Margin" user)
		(31 "F.CrtYd" user "Package Geometry/Place Bound Top")
		(29 "B.CrtYd" user "Package Geometry/Place Bound Bottom")
		(35 "F.Fab" user "Ref Des/Assembly Top")
		(33 "B.Fab" user "Ref Des/Assembly Bottom")
	)
	(footprint ""
		(layer "B.Cu")
		(at 333.346806 -60.368434)
		(property "Reference" "R2U14"
			(at 0 0 0)
			(layer "B.SilkS")
			(hide yes)
			(effects
				(font
					(size 1.27 1.27)
				)
				(justify mirror)
			)
		)
		(property "Value" ""
			(at 0 0 0)
			(layer "B.Fab")
			(effects
				(font
					(size 1.27 1.27)
				)
				(justify mirror)
			)
		)
		(duplicate_pad_numbers_are_jumpers no)
		(fp_poly
			(pts
				(xy 0.2794 -0.1016) (xy -0.2794 -0.1016) (xy -0.2794 0.9906) (xy 0.2794 0.9906)
			)
			(stroke
				(width 0)
				(type default)
			)
			(fill no)
			(layer "B.CrtYd")
		)
		(fp_line
			(start -0.2794 -0.1016)
			(end 0.2794 -0.1016)
			(stroke
				(width 0.1)
				(type default)
			)
			(layer "B.Fab")
		)
		(fp_line
			(start -0.2794 0.9906)
			(end -0.2794 -0.1016)
			(stroke
				(width 0.1)
				(type default)
			)
			(layer "B.Fab")
		)
		(fp_line
			(start 0.2794 -0.1016)
			(end 0.2794 0.9906)
			(stroke
				(width 0.1)
				(type default)
			)
			(layer "B.Fab")
		)
		(fp_line
			(start 0.2794 0.9906)
			(end -0.2794 0.9906)
			(stroke
				(width 0.1)
				(type default)
			)
			(layer "B.Fab")
		)
		(pad "1" smd rect
			(at 0 0 180)
			(size 0.508 0.508)
			(layers "B.Cu" "B.Mask" "B.Paste")
			(net "P3E_CPU0_PE1_SS_RXP<0>")
		)
		(pad "2" smd rect
			(at 0 0.889 180)
			(size 0.508 0.508)
			(layers "B.Cu" "B.Mask" "B.Paste")
			(net "P3E_CPU0_PE1_SS_R_RXP<0>")
		)
		(zone
			(layer "B.Cu")
			(hatch none 0.5)
			(connect_pads
				(clearance 0)
			)
			(min_thickness 0.25)
			(keepout
				(tracks allowed)
				(vias not_allowed)
				(pads allowed)
				(copperpour not_allowed)
				(footprints allowed)
			)
			(placement
				(enabled no)
				(sheetname "")
			)
			(fill
				(thermal_gap 0.5)
				(thermal_bridge_width 0.5)
				(island_removal_mode 0)
			)
			(polygon
				(pts
					(xy 333.600806 -60.114434) (xy 333.092806 -60.114434) (xy 333.092806 -59.733434) (xy 333.600806 -59.733434)
				)
			)
		)
		(zone
			(layer "B.Cu")
			(hatch none 0.5)
			(connect_pads
				(clearance 0)
			)
			(min_thickness 0.25)
			(keepout
				(tracks not_allowed)
				(vias allowed)
				(pads allowed)
				(copperpour not_allowed)
				(footprints allowed)
			)
			(placement
				(enabled no)
				(sheetname "")
			)
			(fill
				(thermal_gap 0.5)
				(thermal_bridge_width 0.5)
				(island_removal_mode 0)
			)
			(polygon
				(pts
					(xy 333.600806 -59.733434) (xy 333.092806 -59.733434) (xy 333.092806 -60.114434) (xy 333.600806 -60.114434)
				)
			)
		)
	)
	(footprint ""
		(layer "B.Cu")
		(at 469.646 -125.984 180)
		(property "Reference" "R1W12"
			(at 0.8382 -0.67818 180)
			(unlocked yes)
			(layer "B.SilkS")
			(effects
				(font
					(size 0.4064 0.254)
					(thickness 0.1524)
				)
				(justify left mirror)
			)
		)
		(property "Value" ""
			(at 0 0 0)
			(layer "B.Fab")
			(effects
				(font
					(size 1.27 1.27)
				)
				(justify mirror)
			)
		)
		(duplicate_pad_numbers_are_jumpers no)
		(fp_poly
			(pts
				(xy 0.2794 -0.1016) (xy -0.2794 -0.1016) (xy -0.2794 0.9906) (xy 0.2794 0.9906)
			)
			(stroke
				(width 0)
				(type default)
			)
			(fill no)
			(layer "B.CrtYd")
		)
		(fp_line
			(start 0.2794 0.9906)
			(end -0.2794 0.9906)
			(stroke
				(width 0.1)
				(type default)
			)
			(layer "B.Fab")
		)
		(fp_line
			(start 0.2794 -0.1016)
			(end 0.2794 0.9906)
			(stroke
				(width 0.1)
				(type default)
			)
			(layer "B.Fab")
		)
		(fp_line
			(start -0.2794 0.9906)
			(end -0.2794 -0.1016)
			(stroke
				(width 0.1)
				(type default)
			)
			(layer "B.Fab")
		)
		(fp_line
			(start -0.2794 -0.1016)
			(end 0.2794 -0.1016)
			(stroke
				(width 0.1)
				(type default)
			)
			(layer "B.Fab")
		)
		(pad "1" smd rect
			(at 0 0)
			(size 0.508 0.508)
			(layers "B.Cu" "B.Mask" "B.Paste")
			(net "FM_CPLD_USB_P0_EN_N")
		)
		(pad "2" smd rect
			(at 0 0.889)
			(size 0.508 0.508)
			(layers "B.Cu" "B.Mask" "B.Paste")
			(net "FM_USB_P0_EN_R_N")
		)
		(zone
			(layer "B.Cu")
			(hatch none 0.5)
			(connect_pads
				(clearance 0)
			)
			(min_thickness 0.25)
			(keepout
				(tracks not_allowed)
				(vias allowed)
				(pads allowed)
				(copperpour not_allowed)
				(footprints allowed)
			)
			(placement
				(enabled no)
				(sheetname "")
			)
			(fill
				(thermal_gap 0.5)
				(thermal_bridge_width 0.5)
				(island_removal_mode 0)
			)
			(polygon
				(pts
					(xy 469.392 -126.619) (xy 469.9 -126.619) (xy 469.9 -126.238) (xy 469.392 -126.238)
				)
			)
		)
		(zone
			(layer "B.Cu")
			(hatch none 0.5)
			(connect_pads
				(clearance 0)
			)
			(min_thickness 0.25)
			(keepout
				(tracks allowed)
				(vias not_allowed)
				(pads allowed)
				(copperpour not_allowed)
				(footprints allowed)
			)
			(placement
				(enabled no)
				(sheetname "")
			)
			(fill
				(thermal_gap 0.5)
				(thermal_bridge_width 0.5)
				(island_removal_mode 0)
			)
			(polygon
				(pts
					(xy 469.392 -126.238) (xy 469.9 -126.238) (xy 469.9 -126.619) (xy 469.392 -126.619)
				)
			)
		)
	)
	(footprint ""
		(layer "B.Cu")
		(at 409.321 -20.828 -90)
		(property "Reference" "R1U28"
			(at 0 0 90)
			(layer "B.SilkS")
			(hide yes)
			(effects
				(font
					(size 1.27 1.27)
				)
				(justify mirror)
			)
		)
		(property "Value" "*"
			(at -0.064008 -4.108196 270)
			(unlocked yes)
			(layer "B.Fab")
			(hide yes)
			(effects
				(font
					(size 1.27 1.016)
					(thickness 0.1524)
				)
				(justify mirror)
			)
		)
		(property "Device Type" "1K82R2F-1-GP_SMD-RG-1K82R2F-1-A"
			(at -0.064008 -5.632196 270)
			(unlocked yes)
			(layer "B.Fab")
			(hide yes)
			(effects
				(font
					(size 1.27 1.016)
					(thickness 0.1524)
				)
				(justify mirror)
			)
		)
		(duplicate_pad_numbers_are_jumpers no)
		(fp_line
			(start -0.508 -0.9398)
			(end 0.508 -0.9398)
			(stroke
				(width 0.1524)
				(type default)
			)
			(layer "B.SilkS")
		)
		(fp_line
			(start 0.508 -0.9398)
			(end 0.508 0.9398)
			(stroke
				(width 0.1524)
				(type default)
			)
			(layer "B.SilkS")
		)
		(fp_rect
			(start 0.508 0.9398)
			(end -0.508 -0.9398)
			(stroke
				(width 0)
				(type default)
			)
			(fill no)
			(layer "B.CrtYd")
		)
		(fp_rect
			(start 0.508 0.9398)
			(end -0.508 -0.9398)
			(stroke
				(width 0)
				(type default)
			)
			(fill no)
			(layer "B.Fab")
		)
		(pad "1" smd custom
			(at 0 -0.4445 90)
			(size 0.1397 0.1397)
			(layers "B.Cu" "B.Mask" "B.Paste")
			(net "A_P5V_SCALED")
			(options
				(clearance outline)
				(anchor circle)
			)
			(primitives
				(gr_poly
					(pts
						(arc
							(start -0.1778 0.2794)
							(mid -0.249642 0.249642)
							(end -0.2794 0.1778)
						)
						(arc
							(start -0.2794 -0.1778)
							(mid -0.249642 -0.249642)
							(end -0.1778 -0.2794)
						)
						(arc
							(start 0.1778 -0.2794)
							(mid 0.249642 -0.249642)
							(end 0.2794 -0.1778)
						)
						(arc
							(start 0.2794 0.1778)
							(mid 0.249642 0.249642)
							(end 0.1778 0.2794)
						)
					)
					(width 0)
					(fill yes)
				)
			)
		)
		(pad "2" smd custom
			(at 0 0.4445 90)
			(size 0.1397 0.1397)
			(layers "B.Cu" "B.Mask" "B.Paste")
			(net "GND")
			(options
				(clearance outline)
				(anchor circle)
			)
			(primitives
				(gr_poly
					(pts
						(arc
							(start -0.1778 0.2794)
							(mid -0.249642 0.249642)
							(end -0.2794 0.1778)
						)
						(arc
							(start -0.2794 -0.1778)
							(mid -0.249642 -0.249642)
							(end -0.1778 -0.2794)
						)
						(arc
							(start 0.1778 -0.2794)
							(mid 0.249642 -0.249642)
							(end 0.2794 -0.1778)
						)
						(arc
							(start 0.2794 0.1778)
							(mid 0.249642 0.249642)
							(end 0.1778 0.2794)
						)
					)
					(width 0)
					(fill yes)
				)
			)
		)
	)
)
